(kicad_pcb
	(version 20260206)
	(generator "pcbnew")
	(generator_version "10.0")
	(general
		(thickness 1.6)
		(legacy_teardrops no)
	)
	(paper "A4")
	(title_block
		(title "fcb — Lightning_FCB_BRD.brd")
		(comment 1 "Lightning (Wiwynn / Facebook NVMe JBOF) / footprints 219-222 of 495")
	)
	(layers
		(0 "F.Cu" signal "TOP")
		(4 "In1.Cu" signal "L2GND")
		(6 "In2.Cu" signal "L3VCC")
		(2 "B.Cu" signal "BOTTOM")
		(9 "F.Adhes" user "F.Adhesive")
		(11 "B.Adhes" user "B.Adhesive")
		(13 "F.Paste" user "Package Geometry/Pastemask Top")
		(15 "B.Paste" user "Package Geometry/Pastemask Bottom")
		(5 "F.SilkS" user "Ref Des/Silkscreen Top")
		(7 "B.SilkS" user "Ref Des/Silkscreen Bottom")
		(1 "F.Mask" user "Board Geometry/Soldermask Top")
		(3 "B.Mask" user "Board Geometry/Soldermask Bottom")
		(17 "Dwgs.User" user "User.Drawings")
		(19 "Cmts.User" user "User.Comments")
		(21 "Eco1.User" user "User.Eco1")
		(23 "Eco2.User" user "User.Eco2")
		(25 "Edge.Cuts" user "Board Geometry/Outline")
		(27 "Margin" user)
		(31 "F.CrtYd" user "Package Geometry/Place Bound Top")
		(29 "B.CrtYd" user "Package Geometry/Place Bound Bottom")
		(35 "F.Fab" user "Ref Des/Assembly Top")
		(33 "B.Fab" user "Ref Des/Assembly Bottom")
	)
	(footprint ""
		(layer "F.Cu")
		(at 41.0464 -139.5222 -90)
		(property "Reference" "PC86"
			(at 0 0 270)
			(layer "F.SilkS")
			(hide yes)
			(effects
				(font
					(size 1.27 1.27)
				)
			)
		)
		(property "Value" "SCD01U25V2KX-3GP"
			(at 1.1811 -2.7051 270)
			(unlocked yes)
			(layer "F.Fab")
			(hide yes)
			(effects
				(font
					(size 1.016 1.016)
					(thickness 0.1524)
				)
			)
		)
		(property "Device Type" "C402H22"
			(at 1.1811 -4.2291 270)
			(unlocked yes)
			(layer "F.Fab")
			(hide yes)
			(effects
				(font
					(size 1.016 1.016)
					(thickness 0.1524)
				)
			)
		)
		(duplicate_pad_numbers_are_jumpers no)
		(fp_rect
			(start -0.4318 0.9525)
			(end 0.4318 -0.9525)
			(stroke
				(width 0)
				(type default)
			)
			(fill no)
			(layer "F.CrtYd")
		)
		(fp_rect
			(start -0.4318 0.9525)
			(end 0.4318 -0.9525)
			(stroke
				(width 0)
				(type default)
			)
			(fill no)
			(layer "F.Fab")
		)
		(pad "1" smd custom
			(at 0 -0.4445 270)
			(size 0.1524 0.1524)
			(layers "F.Cu" "F.Mask" "F.Paste")
			(net "P12VL_2490_RC")
			(options
				(clearance outline)
				(anchor circle)
			)
			(primitives
				(gr_poly
					(pts
						(arc
							(start 0.3048 -0.2032)
							(mid 0.275042 -0.275042)
							(end 0.2032 -0.3048)
						)
						(arc
							(start -0.2032 -0.3048)
							(mid -0.275042 -0.275042)
							(end -0.3048 -0.2032)
						)
						(arc
							(start -0.3048 0.2032)
							(mid -0.275042 0.275042)
							(end -0.2032 0.3048)
						)
						(arc
							(start 0.2032 0.3048)
							(mid 0.275042 0.275042)
							(end 0.3048 0.2032)
						)
					)
					(width 0)
					(fill yes)
				)
			)
		)
		(pad "2" smd custom
			(at 0 0.4445 270)
			(size 0.1524 0.1524)
			(layers "F.Cu" "F.Mask" "F.Paste")
			(net "GND")
			(options
				(clearance outline)
				(anchor circle)
			)
			(primitives
				(gr_poly
					(pts
						(arc
							(start 0.3048 -0.2032)
							(mid 0.275042 -0.275042)
							(end 0.2032 -0.3048)
						)
						(arc
							(start -0.2032 -0.3048)
							(mid -0.275042 -0.275042)
							(end -0.3048 -0.2032)
						)
						(arc
							(start -0.3048 0.2032)
							(mid -0.275042 0.275042)
							(end -0.2032 0.3048)
						)
						(arc
							(start 0.2032 0.3048)
							(mid 0.275042 0.275042)
							(end 0.3048 0.2032)
						)
					)
					(width 0)
					(fill yes)
				)
			)
		)
	)
	(footprint ""
		(layer "F.Cu")
		(at 24.8666 -136.6012 90)
		(property "Reference" "PC89"
			(at 0 0 90)
			(layer "F.SilkS")
			(hide yes)
			(effects
				(font
					(size 1.27 1.27)
				)
			)
		)
		(property "Value" "SCD1U25V2KX-GP"
			(at 1.1811 -2.7051 90)
			(unlocked yes)
			(layer "F.Fab")
			(hide yes)
			(effects
				(font
					(size 1.016 1.016)
					(thickness 0.1524)
				)
			)
		)
		(property "Device Type" "C402H22"
			(at 1.1811 -4.2291 90)
			(unlocked yes)
			(layer "F.Fab")
			(hide yes)
			(effects
				(font
					(size 1.016 1.016)
					(thickness 0.1524)
				)
			)
		)
		(duplicate_pad_numbers_are_jumpers no)
		(fp_rect
			(start -0.4318 0.9525)
			(end 0.4318 -0.9525)
			(stroke
				(width 0)
				(type default)
			)
			(fill no)
			(layer "F.CrtYd")
		)
		(fp_rect
			(start -0.4318 0.9525)
			(end 0.4318 -0.9525)
			(stroke
				(width 0)
				(type default)
			)
			(fill no)
			(layer "F.Fab")
		)
		(pad "1" smd custom
			(at 0 -0.4445 90)
			(size 0.1524 0.1524)
			(layers "F.Cu" "F.Mask" "F.Paste")
			(net "P12VU_2490_VCC")
			(options
				(clearance outline)
				(anchor circle)
			)
			(primitives
				(gr_poly
					(pts
						(arc
							(start 0.3048 -0.2032)
							(mid 0.275042 -0.275042)
							(end 0.2032 -0.3048)
						)
						(arc
							(start -0.2032 -0.3048)
							(mid -0.275042 -0.275042)
							(end -0.3048 -0.2032)
						)
						(arc
							(start -0.3048 0.2032)
							(mid -0.275042 0.275042)
							(end -0.2032 0.3048)
						)
						(arc
							(start 0.2032 0.3048)
							(mid 0.275042 0.275042)
							(end 0.3048 0.2032)
						)
					)
					(width 0)
					(fill yes)
				)
			)
		)
		(pad "2" smd custom
			(at 0 0.4445 90)
			(size 0.1524 0.1524)
			(layers "F.Cu" "F.Mask" "F.Paste")
			(net "GND")
			(options
				(clearance outline)
				(anchor circle)
			)
			(primitives
				(gr_poly
					(pts
						(arc
							(start 0.3048 -0.2032)
							(mid 0.275042 -0.275042)
							(end 0.2032 -0.3048)
						)
						(arc
							(start -0.2032 -0.3048)
							(mid -0.275042 -0.275042)
							(end -0.3048 -0.2032)
						)
						(arc
							(start -0.3048 0.2032)
							(mid -0.275042 0.275042)
							(end -0.2032 0.3048)
						)
						(arc
							(start 0.2032 0.3048)
							(mid 0.275042 0.275042)
							(end 0.3048 0.2032)
						)
					)
					(width 0)
					(fill yes)
				)
			)
		)
	)
	(footprint ""
		(layer "F.Cu")
		(at 19.9136 -149.6822)
		(property "Reference" "R76"
			(at 0 0 0)
			(layer "F.SilkS")
			(hide yes)
			(effects
				(font
					(size 1.27 1.27)
				)
			)
		)
		(property "Value" "10KR2F-2-GP"
			(at 0.064008 -3.993896 0)
			(unlocked yes)
			(layer "F.Fab")
			(hide yes)
			(effects
				(font
					(size 1.016 1.016)
					(thickness 0.1524)
				)
			)
		)
		(property "Device Type" "R402H16"
			(at 0.064008 -5.517896 0)
			(unlocked yes)
			(layer "F.Fab")
			(hide yes)
			(effects
				(font
					(size 1.016 1.016)
					(thickness 0.1524)
				)
			)
		)
		(duplicate_pad_numbers_are_jumpers no)
		(fp_line
			(start -0.508 -0.9398)
			(end -0.508 0.9398)
			(stroke
				(width 0.1524)
				(type default)
			)
			(layer "F.SilkS")
		)
		(fp_line
			(start 0.508 -0.9398)
			(end -0.508 -0.9398)
			(stroke
				(width 0.1524)
				(type default)
			)
			(layer "F.SilkS")
		)
		(fp_rect
			(start -0.508 0.9398)
			(end 0.508 -0.9398)
			(stroke
				(width 0)
				(type default)
			)
			(fill no)
			(layer "F.CrtYd")
		)
		(fp_rect
			(start -0.508 0.9398)
			(end 0.508 -0.9398)
			(stroke
				(width 0)
				(type default)
			)
			(fill no)
			(layer "F.Fab")
		)
		(pad "1" smd custom
			(at 0 -0.4445)
			(size 0.1397 0.1397)
			(layers "F.Cu" "F.Mask" "F.Paste")
			(net "FANIN_9")
			(options
				(clearance outline)
				(anchor circle)
			)
			(primitives
				(gr_poly
					(pts
						(arc
							(start -0.1778 -0.2794)
							(mid -0.249642 -0.249642)
							(end -0.2794 -0.1778)
						)
						(arc
							(start -0.2794 0.1778)
							(mid -0.249642 0.249642)
							(end -0.1778 0.2794)
						)
						(arc
							(start 0.1778 0.2794)
							(mid 0.249642 0.249642)
							(end 0.2794 0.1778)
						)
						(arc
							(start 0.2794 -0.1778)
							(mid 0.249642 -0.249642)
							(end 0.1778 -0.2794)
						)
					)
					(width 0)
					(fill yes)
				)
			)
		)
		(pad "2" smd custom
			(at 0 0.4445)
			(size 0.1397 0.1397)
			(layers "F.Cu" "F.Mask" "F.Paste")
			(net "GND")
			(options
				(clearance outline)
				(anchor circle)
			)
			(primitives
				(gr_poly
					(pts
						(arc
							(start -0.1778 -0.2794)
							(mid -0.249642 -0.249642)
							(end -0.2794 -0.1778)
						)
						(arc
							(start -0.2794 0.1778)
							(mid -0.249642 0.249642)
							(end -0.1778 0.2794)
						)
						(arc
							(start 0.1778 0.2794)
							(mid 0.249642 0.249642)
							(end 0.2794 0.1778)
						)
						(arc
							(start 0.2794 -0.1778)
							(mid 0.249642 -0.249642)
							(end 0.1778 -0.2794)
						)
					)
					(width 0)
					(fill yes)
				)
			)
		)
	)
	(footprint ""
		(layer "F.Cu")
		(at 5.1562 -416.6108 -90)
		(property "Reference" "R28"
			(at 0 0 270)
			(layer "F.SilkS")
			(hide yes)
			(effects
				(font
					(size 1.27 1.27)
				)
			)
		)
		(property "Value" "0R2J-2-GP"
			(at 0.064008 -3.993896 270)
			(unlocked yes)
			(layer "F.Fab")
			(hide yes)
			(effects
				(font
					(size 1.016 1.016)
					(thickness 0.1524)
				)
			)
		)
		(property "Device Type" "R402H16"
			(at 0.064008 -5.517896 270)
			(unlocked yes)
			(layer "F.Fab")
			(hide yes)
			(effects
				(font
					(size 1.016 1.016)
					(thickness 0.1524)
				)
			)
		)
		(duplicate_pad_numbers_are_jumpers no)
		(fp_line
			(start -0.508 -0.9398)
			(end -0.508 0.9398)
			(stroke
				(width 0.1524)
				(type default)
			)
			(layer "F.SilkS")
		)
		(fp_line
			(start 0.508 -0.9398)
			(end -0.508 -0.9398)
			(stroke
				(width 0.1524)
				(type default)
			)
			(layer "F.SilkS")
		)
		(fp_rect
			(start -0.508 0.9398)
			(end 0.508 -0.9398)
			(stroke
				(width 0)
				(type default)
			)
			(fill no)
			(layer "F.CrtYd")
		)
		(fp_rect
			(start -0.508 0.9398)
			(end 0.508 -0.9398)
			(stroke
				(width 0)
				(type default)
			)
			(fill no)
			(layer "F.Fab")
		)
		(pad "1" smd custom
			(at 0 -0.4445 270)
			(size 0.1397 0.1397)
			(layers "F.Cu" "F.Mask" "F.Paste")
			(net "LED_DR_LED1_K")
			(options
				(clearance outline)
				(anchor circle)
			)
			(primitives
				(gr_poly
					(pts
						(arc
							(start -0.1778 -0.2794)
							(mid -0.249642 -0.249642)
							(end -0.2794 -0.1778)
						)
						(arc
							(start -0.2794 0.1778)
							(mid -0.249642 0.249642)
							(end -0.1778 0.2794)
						)
						(arc
							(start 0.1778 0.2794)
							(mid 0.249642 0.249642)
							(end 0.2794 0.1778)
						)
						(arc
							(start 0.2794 -0.1778)
							(mid 0.249642 -0.249642)
							(end 0.1778 -0.2794)
						)
					)
					(width 0)
					(fill yes)
				)
			)
		)
		(pad "2" smd custom
			(at 0 0.4445 270)
			(size 0.1397 0.1397)
			(layers "F.Cu" "F.Mask" "F.Paste")
			(net "GND")
			(options
				(clearance outline)
				(anchor circle)
			)
			(primitives
				(gr_poly
					(pts
						(arc
							(start -0.1778 -0.2794)
							(mid -0.249642 -0.249642)
							(end -0.2794 -0.1778)
						)
						(arc
							(start -0.2794 0.1778)
							(mid -0.249642 0.249642)
							(end -0.1778 0.2794)
						)
						(arc
							(start 0.1778 0.2794)
							(mid 0.249642 0.249642)
							(end 0.2794 0.1778)
						)
						(arc
							(start 0.2794 -0.1778)
							(mid 0.249642 -0.249642)
							(end 0.1778 -0.2794)
						)
					)
					(width 0)
					(fill yes)
				)
			)
		)
	)
)
